# BASEBOARD_FAB2 (Tioga Pass) — schematic netlist excerpt (pin names and nets, part order shuffled) for the footprints in the layout excerpt that follows; sources: Cadence DE-HDL packaged netlist, KiCad conversion of Wiwynn_Tioga_Pass_MB.brd

C3N27  CAP_A  22.0UF 4V 20% X6S  pkg 0603V  page 132 : A = PVNN_PCH_STBY ; B = GND
R3W7  RES  4.75K 1% CHIP  pkg 0402  page 249 : A = P3V3_STBY ; B = VREF_2V2
C25W68  CAP_A  0.1UF 16V 10% X7R  pkg 0402V  page 149 : A = VCC_VA_3V3 ; B = GND

(kicad_pcb
	(version 20260206)
	(generator "pcbnew")
	(generator_version "10.0")
	(general
		(thickness 1.6)
		(legacy_teardrops no)
	)
	(paper "A4")
	(title_block
		(title "Wiwynn_Tioga_Pass_MB.brd")
		(comment 1 "Tioga Pass / footprints 4403-4405 of 4770")
	)
	(layers
		(0 "F.Cu" signal "TOP")
		(4 "In1.Cu" signal "L2GND")
		(6 "In2.Cu" signal "L3")
		(8 "In3.Cu" signal "L4GND")
		(10 "In4.Cu" signal "L5")
		(12 "In5.Cu" signal "L6GND")
		(14 "In6.Cu" signal "L7VCC")
		(16 "In7.Cu" signal "L8VCC")
		(18 "In8.Cu" signal "L9GND")
		(20 "In9.Cu" signal "L10")
		(22 "In10.Cu" signal "L11GND")
		(24 "In11.Cu" signal "L12")
		(26 "In12.Cu" signal "L13GND")
		(2 "B.Cu" signal "BOTTOM")
		(9 "F.Adhes" user "F.Adhesive")
		(11 "B.Adhes" user "B.Adhesive")
		(13 "F.Paste" user "Package Geometry/Pastemask Top")
		(15 "B.Paste" user "Package Geometry/Pastemask Bottom")
		(5 "F.SilkS" user "Ref Des/Silkscreen Top")
		(7 "B.SilkS" user "Ref Des/Silkscreen Bottom")
		(1 "F.Mask" user "Board Geometry/Soldermask Top")
		(3 "B.Mask" user "Board Geometry/Soldermask Bottom")
		(17 "Dwgs.User" user "User.Drawings")
		(19 "Cmts.User" user "User.Comments")
		(21 "Eco1.User" user "User.Eco1")
		(23 "Eco2.User" user "User.Eco2")
		(25 "Edge.Cuts" user "Board Geometry/Outline")
		(27 "Margin" user)
		(31 "F.CrtYd" user "Package Geometry/Place Bound Top")
		(29 "B.CrtYd" user "Package Geometry/Place Bound Bottom")
		(35 "F.Fab" user "Ref Des/Assembly Top")
		(33 "B.Fab" user "Ref Des/Assembly Bottom")
	)
	(footprint ""
		(layer "B.Cu")
		(at 370.1669 -104.8766 90)
		(property "Reference" "C3N27"
			(at 0 0 90)
			(layer "B.SilkS")
			(hide yes)
			(effects
				(font
					(size 1.27 1.27)
				)
				(justify mirror)
			)
		)
		(property "Value" ""
			(at 0 0 90)
			(layer "B.Fab")
			(effects
				(font
					(size 1.27 1.27)
				)
				(justify mirror)
			)
		)
		(duplicate_pad_numbers_are_jumpers no)
		(fp_poly
			(pts
				(xy 0.4953 -0.2032) (xy -0.4953 -0.2032) (xy -0.4953 1.6002) (xy 0.4953 1.6002)
			)
			(stroke
				(width 0)
				(type default)
			)
			(fill no)
			(layer "B.CrtYd")
		)
		(fp_line
			(start 0.4953 -0.2032)
			(end -0.4953 -0.2032)
			(stroke
				(width 0.1)
				(type default)
			)
			(layer "B.Fab")
		)
		(fp_line
			(start -0.4953 -0.2032)
			(end -0.4953 1.6002)
			(stroke
				(width 0.1)
				(type default)
			)
			(layer "B.Fab")
		)
		(fp_line
			(start 0.4953 1.6002)
			(end 0.4953 -0.2032)
			(stroke
				(width 0.1)
				(type default)
			)
			(layer "B.Fab")
		)
		(fp_line
			(start -0.4953 1.6002)
			(end 0.4953 1.6002)
			(stroke
				(width 0.1)
				(type default)
			)
			(layer "B.Fab")
		)
		(pad "1" smd rect
			(at 0 0 270)
			(size 0.762 0.889)
			(layers "B.Cu" "B.Mask" "B.Paste")
			(net "PVNN_PCH_STBY")
		)
		(pad "2" smd rect
			(at 0 1.397 270)
			(size 0.762 0.889)
			(layers "B.Cu" "B.Mask" "B.Paste")
			(net "GND")
		)
		(zone
			(layer "B.Cu")
			(hatch none 0.5)
			(connect_pads
				(clearance 0)
			)
			(min_thickness 0.25)
			(keepout
				(tracks not_allowed)
				(vias allowed)
				(pads allowed)
				(copperpour not_allowed)
				(footprints allowed)
			)
			(placement
				(enabled no)
				(sheetname "")
			)
			(fill
				(thermal_gap 0.5)
				(thermal_bridge_width 0.5)
				(island_removal_mode 0)
			)
			(polygon
				(pts
					(xy 370.6114 -105.2576) (xy 370.6114 -104.4956) (xy 371.1194 -104.4956) (xy 371.1194 -105.2576)
				)
			)
		)
	)
	(footprint ""
		(layer "B.Cu")
		(at 446.9892 -17.3482 90)
		(property "Reference" "R3W7"
			(at 0.8382 -0.67818 90)
			(unlocked yes)
			(layer "B.SilkS")
			(effects
				(font
					(size 0.4064 0.254)
					(thickness 0.1524)
				)
				(justify left mirror)
			)
		)
		(property "Value" ""
			(at 0 0 90)
			(layer "B.Fab")
			(effects
				(font
					(size 1.27 1.27)
				)
				(justify mirror)
			)
		)
		(duplicate_pad_numbers_are_jumpers no)
		(fp_poly
			(pts
				(xy 0.2794 -0.1016) (xy -0.2794 -0.1016) (xy -0.2794 0.9906) (xy 0.2794 0.9906)
			)
			(stroke
				(width 0)
				(type default)
			)
			(fill no)
			(layer "B.CrtYd")
		)
		(fp_line
			(start 0.2794 -0.1016)
			(end 0.2794 0.9906)
			(stroke
				(width 0.1)
				(type default)
			)
			(layer "B.Fab")
		)
		(fp_line
			(start -0.2794 -0.1016)
			(end 0.2794 -0.1016)
			(stroke
				(width 0.1)
				(type default)
			)
			(layer "B.Fab")
		)
		(fp_line
			(start 0.2794 0.9906)
			(end -0.2794 0.9906)
			(stroke
				(width 0.1)
				(type default)
			)
			(layer "B.Fab")
		)
		(fp_line
			(start -0.2794 0.9906)
			(end -0.2794 -0.1016)
			(stroke
				(width 0.1)
				(type default)
			)
			(layer "B.Fab")
		)
		(pad "1" smd rect
			(at 0 0 270)
			(size 0.508 0.508)
			(layers "B.Cu" "B.Mask" "B.Paste")
			(net "P3V3_STBY")
		)
		(pad "2" smd rect
			(at 0 0.889 270)
			(size 0.508 0.508)
			(layers "B.Cu" "B.Mask" "B.Paste")
			(net "VREF_2V2")
		)
		(zone
			(layer "B.Cu")
			(hatch none 0.5)
			(connect_pads
				(clearance 0)
			)
			(min_thickness 0.25)
			(keepout
				(tracks allowed)
				(vias not_allowed)
				(pads allowed)
				(copperpour not_allowed)
				(footprints allowed)
			)
			(placement
				(enabled no)
				(sheetname "")
			)
			(fill
				(thermal_gap 0.5)
				(thermal_bridge_width 0.5)
				(island_removal_mode 0)
			)
			(polygon
				(pts
					(xy 447.2432 -17.6022) (xy 447.2432 -17.0942) (xy 447.6242 -17.0942) (xy 447.6242 -17.6022)
				)
			)
		)
		(zone
			(layer "B.Cu")
			(hatch none 0.5)
			(connect_pads
				(clearance 0)
			)
			(min_thickness 0.25)
			(keepout
				(tracks not_allowed)
				(vias allowed)
				(pads allowed)
				(copperpour not_allowed)
				(footprints allowed)
			)
			(placement
				(enabled no)
				(sheetname "")
			)
			(fill
				(thermal_gap 0.5)
				(thermal_bridge_width 0.5)
				(island_removal_mode 0)
			)
			(polygon
				(pts
					(xy 447.6242 -17.6022) (xy 447.6242 -17.0942) (xy 447.2432 -17.0942) (xy 447.2432 -17.6022)
				)
			)
		)
	)
	(footprint ""
		(layer "B.Cu")
		(at 411.324552 -29.55036 90)
		(property "Reference" "C25W68"
			(at 0.8382 -0.67818 90)
			(unlocked yes)
			(layer "B.SilkS")
			(effects
				(font
					(size 0.4064 0.254)
					(thickness 0.1524)
				)
				(justify left mirror)
			)
		)
		(property "Value" ""
			(at 0 0 90)
			(layer "B.Fab")
			(effects
				(font
					(size 1.27 1.27)
				)
				(justify mirror)
			)
		)
		(duplicate_pad_numbers_are_jumpers no)
		(fp_poly
			(pts
				(xy -0.3048 -0.1016) (xy -0.3048 0.9906) (xy 0.3048 0.9906) (xy 0.3048 -0.1016)
			)
			(stroke
				(width 0)
				(type default)
			)
			(fill no)
			(layer "B.CrtYd")
		)
		(fp_line
			(start 0.3048 -0.1016)
			(end 0.3048 0.9906)
			(stroke
				(width 0.1)
				(type default)
			)
			(layer "B.Fab")
		)
		(fp_line
			(start -0.3048 -0.1016)
			(end 0.3048 -0.1016)
			(stroke
				(width 0.1)
				(type default)
			)
			(layer "B.Fab")
		)
		(fp_line
			(start 0.3048 0.9906)
			(end -0.3048 0.9906)
			(stroke
				(width 0.1)
				(type default)
			)
			(layer "B.Fab")
		)
		(fp_line
			(start -0.3048 0.9906)
			(end -0.3048 -0.1016)
			(stroke
				(width 0.1)
				(type default)
			)
			(layer "B.Fab")
		)
		(pad "1" smd rect
			(at 0 0 270)
			(size 0.508 0.508)
			(layers "B.Cu" "B.Mask" "B.Paste")
			(net "VCC_VA_3V3")
		)
		(pad "2" smd rect
			(at 0 0.889 270)
			(size 0.508 0.508)
			(layers "B.Cu" "B.Mask" "B.Paste")
			(net "GND")
		)
		(zone
			(layer "B.Cu")
			(hatch none 0.5)
			(connect_pads
				(clearance 0)
			)
			(min_thickness 0.25)
			(keepout
				(tracks allowed)
				(vias not_allowed)
				(pads allowed)
				(copperpour not_allowed)
				(footprints allowed)
			)
			(placement
				(enabled no)
				(sheetname "")
			)
			(fill
				(thermal_gap 0.5)
				(thermal_bridge_width 0.5)
				(island_removal_mode 0)
			)
			(polygon
				(pts
					(xy 411.578552 -29.80436) (xy 411.578552 -29.29636) (xy 411.959552 -29.29636) (xy 411.959552 -29.80436)
				)
			)
		)
		(zone
			(layer "B.Cu")
			(hatch none 0.5)
			(connect_pads
				(clearance 0)
			)
			(min_thickness 0.25)
			(keepout
				(tracks not_allowed)
				(vias allowed)
				(pads allowed)
				(copperpour not_allowed)
				(footprints allowed)
			)
			(placement
				(enabled no)
				(sheetname "")
			)
			(fill
				(thermal_gap 0.5)
				(thermal_bridge_width 0.5)
				(island_removal_mode 0)
			)
			(polygon
				(pts
					(xy 411.959552 -29.80436) (xy 411.959552 -29.29636) (xy 411.578552 -29.29636) (xy 411.578552 -29.80436)
				)
			)
		)
	)
)
